(kicad_pcb
	(version 20260206)
	(generator "pcbnew")
	(generator_version "10.0")
	(general
		(thickness 1.21888)
		(legacy_teardrops no)
	)
	(paper "A4")
	(title_block
		(title "timecard-v7 — TimeCard-DC-V7_EXP.PcbDoc")
		(comment 1 "Time Appliance Project (Time Card) / footprints 60-63 of 160")
	)
	(layers
		(0 "F.Cu" signal "TOP")
		(4 "In1.Cu" signal "SGND")
		(6 "In2.Cu" signal "IN1")
		(8 "In3.Cu" signal "IN2")
		(10 "In4.Cu" signal "SGND1")
		(2 "B.Cu" signal "BOTTOM")
		(9 "F.Adhes" user "F.Adhesive")
		(11 "B.Adhes" user "B.Adhesive")
		(13 "F.Paste" user "Top Paste")
		(15 "B.Paste" user "Bottom Paste")
		(5 "F.SilkS" user "Top Overlay")
		(7 "B.SilkS" user "Bottom Overlay")
		(1 "F.Mask" user "Top Solder")
		(3 "B.Mask" user "Bottom Solder")
		(17 "Dwgs.User" user "User.Drawings")
		(19 "Cmts.User" user "User.Comments")
		(21 "Eco1.User" user "User.Eco1")
		(23 "Eco2.User" user "User.Eco2")
		(25 "Edge.Cuts" user)
		(27 "Margin" user)
		(31 "F.CrtYd" user "Top Courtyard")
		(29 "B.CrtYd" user "Bottom Courtyard")
		(35 "F.Fab" user "Top Component Center")
		(33 "B.Fab" user "Bottom Component Center")
	)
	(footprint "Passives:SOT65P210X110-3N"
		(layer "F.Cu")
		(at 195.11136 139.37763)
		(property "Reference" "D5"
			(at -3.38526 -0.968085 0)
			(unlocked yes)
			(layer "F.SilkS")
			(effects
				(font
					(size 0.762 0.762)
					(thickness 0.2286)
				)
				(justify left bottom)
			)
		)
		(property "Value" "BAT54SW"
			(at -10.7749 -6.23021 0)
			(unlocked yes)
			(layer "F.SilkS")
			(hide yes)
			(effects
				(font
					(size 1.524 1.524)
					(thickness 0.254)
				)
				(justify left bottom)
			)
		)
		(sheetname "PCIe_JTAG")
		(sheetfile "PCIe_JTAG.kicad_sch")
		(duplicate_pad_numbers_are_jumpers no)
		(fp_line
			(start -0.325 -1.1)
			(end 0.675 -1.1)
			(stroke
				(width 0.2)
				(type solid)
			)
			(layer "F.SilkS")
		)
		(fp_line
			(start -0.325 1.1)
			(end 0.675 1.1)
			(stroke
				(width 0.2)
				(type solid)
			)
			(layer "F.SilkS")
		)
		(fp_line
			(start 0.675 -0.65)
			(end 0.675 -1.1)
			(stroke
				(width 0.2)
				(type solid)
			)
			(layer "F.SilkS")
		)
		(fp_line
			(start 0.675 1.1)
			(end 0.675 0.65)
			(stroke
				(width 0.2)
				(type solid)
			)
			(layer "F.SilkS")
		)
		(fp_circle
			(center -1.125 -1.45)
			(end -1.125 -1.575)
			(stroke
				(width 0.25)
				(type solid)
			)
			(fill no)
			(layer "F.SilkS")
		)
		(pad "1" smd rect
			(at -1.125 -0.65 90)
			(size 0.5 0.9)
			(layers "F.Cu" "F.Mask" "F.Paste")
			(net "GND")
		)
		(pad "2" smd rect
			(at -1.125 0.65 90)
			(size 0.5 0.9)
			(layers "F.Cu" "F.Mask" "F.Paste")
			(net "+3.3V")
		)
		(pad "3" smd rect
			(at 1.125 0 90)
			(size 0.5 0.9)
			(layers "F.Cu" "F.Mask" "F.Paste")
			(net "FPGA_TCK")
		)
	)
	(footprint "Vault:CAPC1608X87X45ML20T05"
		(layer "F.Cu")
		(at 213.4735 116.3062 90)
		(property "Reference" "C17"
			(at 1.74 0.708345 90)
			(unlocked yes)
			(layer "F.SilkS")
			(effects
				(font
					(size 0.762 0.762)
					(thickness 0.2286)
				)
				(justify left bottom)
			)
		)
		(property "Value" "0.1uF"
			(at -6.58639 0.0755 0)
			(unlocked yes)
			(layer "F.SilkS")
			(hide yes)
			(effects
				(font
					(size 1.524 1.524)
					(thickness 0.254)
				)
				(justify left bottom)
			)
		)
		(sheetname "POWER")
		(sheetfile "POWER.kicad_sch")
		(duplicate_pad_numbers_are_jumpers no)
		(pad "1" smd rect
			(at -0.7 0 180)
			(size 1.1 1.05)
			(layers "F.Cu" "F.Mask" "F.Paste")
			(net "GND")
		)
		(pad "2" smd rect
			(at 0.7 0 180)
			(size 1.1 1.05)
			(layers "F.Cu" "F.Mask" "F.Paste")
			(net "+5.0V")
		)
	)
	(footprint "FPGA_CONN:SingleFPGAConn"
		(layer "F.Cu")
		(at 149.7158 124.56234)
		(property "Reference" "J36"
			(at -0.368955 -23.428198 0)
			(unlocked yes)
			(layer "F.SilkS")
			(effects
				(font
					(size 1.524 1.524)
					(thickness 0.254)
				)
			)
		)
		(property "Value" "Single FPGA Conn"
			(at 9.27992 3.521202 0)
			(unlocked yes)
			(layer "F.SilkS")
			(hide yes)
			(effects
				(font
					(size 1.524 1.524)
					(thickness 0.254)
				)
			)
		)
		(sheetname "FPGA")
		(sheetfile "FPGA.kicad_sch")
		(duplicate_pad_numbers_are_jumpers no)
		(fp_line
			(start -1.99999 -20.69998)
			(end -1.40005 -20.69998)
			(stroke
				(width 0.15011)
				(type solid)
			)
			(layer "F.SilkS")
		)
		(fp_line
			(start -1.99999 -20.03298)
			(end -1.99999 -20.69998)
			(stroke
				(width 0.15011)
				(type solid)
			)
			(layer "F.SilkS")
		)
		(fp_line
			(start -1.99999 0.70003)
			(end -1.99999 0.03302)
			(stroke
				(width 0.15011)
				(type solid)
			)
			(layer "F.SilkS")
		)
		(fp_line
			(start -1.99999 0.70003)
			(end -1.40005 0.70003)
			(stroke
				(width 0.15011)
				(type solid)
			)
			(layer "F.SilkS")
		)
		(fp_line
			(start -1.40005 -21.24989)
			(end 1.40005 -21.24989)
			(stroke
				(width 0.15011)
				(type solid)
			)
			(layer "F.SilkS")
		)
		(fp_line
			(start -1.40005 -20.69998)
			(end -1.40005 -21.24989)
			(stroke
				(width 0.15011)
				(type solid)
			)
			(layer "F.SilkS")
		)
		(fp_line
			(start -1.40005 1.24994)
			(end -1.40005 0.70003)
			(stroke
				(width 0.15011)
				(type solid)
			)
			(layer "F.SilkS")
		)
		(fp_line
			(start -1.40005 1.24994)
			(end 1.40005 1.24994)
			(stroke
				(width 0.15011)
				(type solid)
			)
			(layer "F.SilkS")
		)
		(fp_line
			(start 1.40005 -20.69998)
			(end 1.40005 -21.24989)
			(stroke
				(width 0.15011)
				(type solid)
			)
			(layer "F.SilkS")
		)
		(fp_line
			(start 1.40005 -20.69998)
			(end 2 -20.69998)
			(stroke
				(width 0.15011)
				(type solid)
			)
			(layer "F.SilkS")
		)
		(fp_line
			(start 1.40005 0.70003)
			(end 2 0.70003)
			(stroke
				(width 0.15011)
				(type solid)
			)
			(layer "F.SilkS")
		)
		(fp_line
			(start 1.40005 1.24994)
			(end 1.40005 0.70003)
			(stroke
				(width 0.15011)
				(type solid)
			)
			(layer "F.SilkS")
		)
		(fp_line
			(start 2 -20.03298)
			(end 2 -20.69998)
			(stroke
				(width 0.15011)
				(type solid)
			)
			(layer "F.SilkS")
		)
		(fp_line
			(start 2 0.70003)
			(end 2 0.03302)
			(stroke
				(width 0.15011)
				(type solid)
			)
			(layer "F.SilkS")
		)
		(fp_circle
			(center 3.5052 -0.22453)
			(end 3.5052 -0.42468)
			(stroke
				(width 0.40005)
				(type solid)
			)
			(fill no)
			(layer "F.SilkS")
		)
		(pad "1" smd rect
			(at 2.02489 -0.24993)
			(size 1.54991 0.24994)
			(layers "F.Cu" "F.Mask" "F.Paste")
			(net "GPS2_TX")
		)
		(pad "2" smd rect
			(at -2.02489 -0.24993)
			(size 1.54991 0.24994)
			(layers "F.Cu" "F.Mask" "F.Paste")
			(net "GPS2_RX")
		)
		(pad "3" smd rect
			(at 2.02489 -0.75006)
			(size 1.54991 0.24994)
			(layers "F.Cu" "F.Mask" "F.Paste")
		)
		(pad "4" smd rect
			(at -2.02489 -0.75006)
			(size 1.54991 0.24994)
			(layers "F.Cu" "F.Mask" "F.Paste")
		)
		(pad "5" smd rect
			(at 2.02489 -1.24993)
			(size 1.54991 0.24994)
			(layers "F.Cu" "F.Mask" "F.Paste")
			(net "GPS2_TP1")
		)
		(pad "6" smd rect
			(at -2.02489 -1.24993)
			(size 1.54991 0.24994)
			(layers "F.Cu" "F.Mask" "F.Paste")
		)
		(pad "7" smd rect
			(at 2.02489 -1.75006)
			(size 1.54991 0.24994)
			(layers "F.Cu" "F.Mask" "F.Paste")
			(net "GPS2_TP2")
		)
		(pad "8" smd rect
			(at -2.02489 -1.75006)
			(size 1.54991 0.24994)
			(layers "F.Cu" "F.Mask" "F.Paste")
		)
		(pad "9" smd rect
			(at 2.02489 -2.24993)
			(size 1.54991 0.24994)
			(layers "F.Cu" "F.Mask" "F.Paste")
			(net "GND")
		)
		(pad "10" smd rect
			(at -2.02489 -2.24993)
			(size 1.54991 0.24994)
			(layers "F.Cu" "F.Mask" "F.Paste")
			(net "GND")
		)
		(pad "11" smd rect
			(at 2.02489 -2.75006)
			(size 1.54991 0.24994)
			(layers "F.Cu" "F.Mask" "F.Paste")
			(net "GPS2_RST")
		)
		(pad "12" smd rect
			(at -2.02489 -2.75006)
			(size 1.54991 0.24994)
			(layers "F.Cu" "F.Mask" "F.Paste")
			(net "IO_LED1")
		)
		(pad "13" smd rect
			(at 2.02489 -3.24993)
			(size 1.54991 0.24994)
			(layers "F.Cu" "F.Mask" "F.Paste")
		)
		(pad "14" smd rect
			(at -2.02489 -3.24993)
			(size 1.54991 0.24994)
			(layers "F.Cu" "F.Mask" "F.Paste")
			(net "IO_LED2")
		)
		(pad "15" smd rect
			(at 2.02489 -3.75005)
			(size 1.54991 0.24994)
			(layers "F.Cu" "F.Mask" "F.Paste")
		)
		(pad "16" smd rect
			(at -2.02489 -3.75005)
			(size 1.54991 0.24994)
			(layers "F.Cu" "F.Mask" "F.Paste")
			(net "IO_LED3")
		)
		(pad "17" smd rect
			(at 2.02489 -4.24993)
			(size 1.54991 0.24994)
			(layers "F.Cu" "F.Mask" "F.Paste")
		)
		(pad "18" smd rect
			(at -2.02489 -4.24993)
			(size 1.54991 0.24994)
			(layers "F.Cu" "F.Mask" "F.Paste")
			(net "IO_LED4")
		)
		(pad "19" smd rect
			(at 2.02489 -4.75005)
			(size 1.54991 0.24994)
			(layers "F.Cu" "F.Mask" "F.Paste")
			(net "GND")
		)
		(pad "20" smd rect
			(at -2.02489 -4.75005)
			(size 1.54991 0.24994)
			(layers "F.Cu" "F.Mask" "F.Paste")
			(net "GND")
		)
		(pad "21" smd rect
			(at 2.02489 -5.24992)
			(size 1.54991 0.24994)
			(layers "F.Cu" "F.Mask" "F.Paste")
			(net "PCIE_PERST")
		)
		(pad "22" smd rect
			(at -2.02489 -5.24992)
			(size 1.54991 0.24994)
			(layers "F.Cu" "F.Mask" "F.Paste")
		)
		(pad "23" smd rect
			(at 2.02489 -5.75005)
			(size 1.54991 0.24994)
			(layers "F.Cu" "F.Mask" "F.Paste")
			(net "KEY1")
		)
		(pad "24" smd rect
			(at -2.02489 -5.75005)
			(size 1.54991 0.24994)
			(layers "F.Cu" "F.Mask" "F.Paste")
		)
		(pad "25" smd rect
			(at 2.02489 -6.24992)
			(size 1.54991 0.24994)
			(layers "F.Cu" "F.Mask" "F.Paste")
		)
		(pad "26" smd rect
			(at -2.02489 -6.24992)
			(size 1.54991 0.24994)
			(layers "F.Cu" "F.Mask" "F.Paste")
		)
		(pad "27" smd rect
			(at 2.02489 -6.75005)
			(size 1.54991 0.24994)
			(layers "F.Cu" "F.Mask" "F.Paste")
		)
		(pad "28" smd rect
			(at -2.02489 -6.75005)
			(size 1.54991 0.24994)
			(layers "F.Cu" "F.Mask" "F.Paste")
		)
		(pad "29" smd rect
			(at 2.02489 -7.24992)
			(size 1.54991 0.24994)
			(layers "F.Cu" "F.Mask" "F.Paste")
			(net "GND")
		)
		(pad "30" smd rect
			(at -2.02489 -7.24992)
			(size 1.54991 0.24994)
			(layers "F.Cu" "F.Mask" "F.Paste")
			(net "GND")
		)
		(pad "31" smd rect
			(at 2.02489 -7.75005)
			(size 1.54991 0.24994)
			(layers "F.Cu" "F.Mask" "F.Paste")
			(net "ANT1_IO_OUT")
		)
		(pad "32" smd rect
			(at -2.02489 -7.75005)
			(size 1.54991 0.24994)
			(layers "F.Cu" "F.Mask" "F.Paste")
			(net "EXT_GPIO_7")
		)
		(pad "33" smd rect
			(at 2.02489 -8.24992)
			(size 1.54991 0.24994)
			(layers "F.Cu" "F.Mask" "F.Paste")
			(net "ANT1_IO_IN")
		)
		(pad "34" smd rect
			(at -2.02489 -8.24992)
			(size 1.54991 0.24994)
			(layers "F.Cu" "F.Mask" "F.Paste")
			(net "EXT_GPIO_8")
		)
		(pad "35" smd rect
			(at 2.02489 -8.75004)
			(size 1.54991 0.24994)
			(layers "F.Cu" "F.Mask" "F.Paste")
			(net "ANT2_IO_OUT")
		)
		(pad "36" smd rect
			(at -2.02489 -8.75004)
			(size 1.54991 0.24994)
			(layers "F.Cu" "F.Mask" "F.Paste")
			(net "EXT_GPIO_9")
		)
		(pad "37" smd rect
			(at 2.02489 -9.24992)
			(size 1.54991 0.24994)
			(layers "F.Cu" "F.Mask" "F.Paste")
			(net "ANT2_IO_IN")
		)
		(pad "38" smd rect
			(at -2.02489 -9.24992)
			(size 1.54991 0.24994)
			(layers "F.Cu" "F.Mask" "F.Paste")
			(net "EXT_GPIO_10")
		)
		(pad "39" smd rect
			(at 2.02489 -9.75004)
			(size 1.54991 0.24994)
			(layers "F.Cu" "F.Mask" "F.Paste")
			(net "GND")
		)
		(pad "40" smd rect
			(at -2.02489 -9.75004)
			(size 1.54991 0.24994)
			(layers "F.Cu" "F.Mask" "F.Paste")
			(net "GND")
		)
		(pad "41" smd rect
			(at 2.02489 -10.24991)
			(size 1.54991 0.24994)
			(layers "F.Cu" "F.Mask" "F.Paste")
			(net "ANT3_IO_OUT")
		)
		(pad "42" smd rect
			(at -2.02489 -10.24991)
			(size 1.54991 0.24994)
			(layers "F.Cu" "F.Mask" "F.Paste")
			(net "EXT_GPIO_1")
		)
		(pad "43" smd rect
			(at 2.02489 -10.75004)
			(size 1.54991 0.24994)
			(layers "F.Cu" "F.Mask" "F.Paste")
			(net "ANT3_IO_IN")
		)
		(pad "44" smd rect
			(at -2.02489 -10.75004)
			(size 1.54991 0.24994)
			(layers "F.Cu" "F.Mask" "F.Paste")
			(net "EXT_GPIO_2")
		)
		(pad "45" smd rect
			(at 2.02489 -11.24991)
			(size 1.54991 0.24994)
			(layers "F.Cu" "F.Mask" "F.Paste")
			(net "ANT4_IO_OUT")
		)
		(pad "46" smd rect
			(at -2.02489 -11.24991)
			(size 1.54991 0.24994)
			(layers "F.Cu" "F.Mask" "F.Paste")
			(net "EXT_GPIO_3")
		)
		(pad "47" smd rect
			(at 2.02489 -11.75004)
			(size 1.54991 0.24994)
			(layers "F.Cu" "F.Mask" "F.Paste")
			(net "ANT4_IO_IN")
		)
		(pad "48" smd rect
			(at -2.02489 -11.75004)
			(size 1.54991 0.24994)
			(layers "F.Cu" "F.Mask" "F.Paste")
			(net "EXT_GPIO_4")
		)
		(pad "49" smd rect
			(at 2.02489 -12.24991)
			(size 1.54991 0.24994)
			(layers "F.Cu" "F.Mask" "F.Paste")
			(net "GND")
		)
		(pad "50" smd rect
			(at -2.02489 -12.24991)
			(size 1.54991 0.24994)
			(layers "F.Cu" "F.Mask" "F.Paste")
			(net "GND")
		)
		(pad "51" smd rect
			(at 2.02489 -12.75004)
			(size 1.54991 0.24994)
			(layers "F.Cu" "F.Mask" "F.Paste")
		)
		(pad "52" smd rect
			(at -2.02489 -12.75004)
			(size 1.54991 0.24994)
			(layers "F.Cu" "F.Mask" "F.Paste")
		)
		(pad "53" smd rect
			(at 2.02489 -13.24991)
			(size 1.54991 0.24994)
			(layers "F.Cu" "F.Mask" "F.Paste")
		)
		(pad "54" smd rect
			(at -2.02489 -13.24991)
			(size 1.54991 0.24994)
			(layers "F.Cu" "F.Mask" "F.Paste")
		)
		(pad "55" smd rect
			(at 2.02489 -13.75003)
			(size 1.54991 0.24994)
			(layers "F.Cu" "F.Mask" "F.Paste")
		)
		(pad "56" smd rect
			(at -2.02489 -13.75003)
			(size 1.54991 0.24994)
			(layers "F.Cu" "F.Mask" "F.Paste")
		)
		(pad "57" smd rect
			(at 2.02489 -14.24991)
			(size 1.54991 0.24994)
			(layers "F.Cu" "F.Mask" "F.Paste")
		)
		(pad "58" smd rect
			(at -2.02489 -14.24991)
			(size 1.54991 0.24994)
			(layers "F.Cu" "F.Mask" "F.Paste")
		)
		(pad "59" smd rect
			(at 2.02489 -14.75003)
			(size 1.54991 0.24994)
			(layers "F.Cu" "F.Mask" "F.Paste")
			(net "GND")
		)
		(pad "60" smd rect
			(at -2.02489 -14.75003)
			(size 1.54991 0.24994)
			(layers "F.Cu" "F.Mask" "F.Paste")
			(net "GND")
		)
		(pad "61" smd rect
			(at 2.02489 -15.2499)
			(size 1.54991 0.24994)
			(layers "F.Cu" "F.Mask" "F.Paste")
		)
		(pad "62" smd rect
			(at -2.02489 -15.2499)
			(size 1.54991 0.24994)
			(layers "F.Cu" "F.Mask" "F.Paste")
		)
		(pad "63" smd rect
			(at 2.02489 -15.75003)
			(size 1.54991 0.24994)
			(layers "F.Cu" "F.Mask" "F.Paste")
		)
		(pad "64" smd rect
			(at -2.02489 -15.75003)
			(size 1.54991 0.24994)
			(layers "F.Cu" "F.Mask" "F.Paste")
		)
		(pad "65" smd rect
			(at 2.02489 -16.2499)
			(size 1.54991 0.24994)
			(layers "F.Cu" "F.Mask" "F.Paste")
		)
		(pad "66" smd rect
			(at -2.02489 -16.2499)
			(size 1.54991 0.24994)
			(layers "F.Cu" "F.Mask" "F.Paste")
		)
		(pad "67" smd rect
			(at 2.02489 -16.75003)
			(size 1.54991 0.24994)
			(layers "F.Cu" "F.Mask" "F.Paste")
		)
		(pad "68" smd rect
			(at -2.02489 -16.75003)
			(size 1.54991 0.24994)
			(layers "F.Cu" "F.Mask" "F.Paste")
		)
		(pad "69" smd rect
			(at 2.02489 -17.2499)
			(size 1.54991 0.24994)
			(layers "F.Cu" "F.Mask" "F.Paste")
			(net "GND")
		)
		(pad "70" smd rect
			(at -2.02489 -17.2499)
			(size 1.54991 0.24994)
			(layers "F.Cu" "F.Mask" "F.Paste")
			(net "GND")
		)
		(pad "71" smd rect
			(at 2.02489 -17.75003)
			(size 1.54991 0.24994)
			(layers "F.Cu" "F.Mask" "F.Paste")
		)
		(pad "72" smd rect
			(at -2.02489 -17.75003)
			(size 1.54991 0.24994)
			(layers "F.Cu" "F.Mask" "F.Paste")
		)
		(pad "73" smd rect
			(at 2.02489 -18.2499)
			(size 1.54991 0.24994)
			(layers "F.Cu" "F.Mask" "F.Paste")
		)
		(pad "74" smd rect
			(at -2.02489 -18.2499)
			(size 1.54991 0.24994)
			(layers "F.Cu" "F.Mask" "F.Paste")
		)
		(pad "75" smd rect
			(at 2.02489 -18.75002)
			(size 1.54991 0.24994)
			(layers "F.Cu" "F.Mask" "F.Paste")
		)
		(pad "76" smd rect
			(at -2.02489 -18.75002)
			(size 1.54991 0.24994)
			(layers "F.Cu" "F.Mask" "F.Paste")
		)
		(pad "77" smd rect
			(at 2.02489 -19.2499)
			(size 1.54991 0.24994)
			(layers "F.Cu" "F.Mask" "F.Paste")
			(net "FPGA_TCK")
		)
		(pad "78" smd rect
			(at -2.02489 -19.2499)
			(size 1.54991 0.24994)
			(layers "F.Cu" "F.Mask" "F.Paste")
			(net "FPGA_TDI")
		)
		(pad "79" smd rect
			(at 2.02489 -19.75002)
			(size 1.54991 0.24994)
			(layers "F.Cu" "F.Mask" "F.Paste")
			(net "FPGA_TDO")
		)
		(pad "80" smd rect
			(at -2.02489 -19.75002)
			(size 1.54991 0.24994)
			(layers "F.Cu" "F.Mask" "F.Paste")
			(net "FPGA_TMS")
		)
		(pad "81" smd rect
			(at 0.01136 1.17626)
			(size 1.70002 1.35001)
			(layers "F.Cu" "F.Mask" "F.Paste")
		)
		(pad "82" thru_hole circle
			(at 0 0)
			(size 0.55016 0.55016)
			(drill 0.55016)
			(layers "*.Cu" "*.Mask")
			(remove_unused_layers no)
			(thermal_bridge_angle 90)
		)
		(pad "83" thru_hole circle
			(at 0 -19.99996)
			(size 0.55016 0.55016)
			(drill 0.55016)
			(layers "*.Cu" "*.Mask")
			(remove_unused_layers no)
			(thermal_bridge_angle 90)
		)
		(pad "84" smd rect
			(at 0.01136 -21.17374)
			(size 1.70002 1.35001)
			(layers "F.Cu" "F.Mask" "F.Paste")
		)
	)
	(footprint "Vault:AMPH-901-143-6RFX_V"
		(layer "F.Cu")
		(at 60.9761 135.5786 180)
		(property "Reference" "AN4"
			(at -5.817355 2.786 90)
			(unlocked yes)
			(layer "F.SilkS")
			(effects
				(font
					(size 0.762 0.762)
					(thickness 0.2286)
				)
				(justify left bottom)
			)
		)
		(property "Value" "901-143-6RFX"
			(at 4.6101 -12.21359 0)
			(unlocked yes)
			(layer "F.SilkS")
			(hide yes)
			(effects
				(font
					(size 1.524 1.524)
					(thickness 0.254)
				)
				(justify left bottom)
			)
		)
		(sheetname "USER_IO")
		(sheetfile "USER_IO.kicad_sch")
		(duplicate_pad_numbers_are_jumpers no)
		(fp_line
			(start 3.5 -1.38)
			(end 3.5 1.38)
			(stroke
				(width 0.2)
				(type solid)
			)
			(layer "F.SilkS")
		)
		(fp_line
			(start 1.38 3.5)
			(end -1.38 3.5)
			(stroke
				(width 0.2)
				(type solid)
			)
			(layer "F.SilkS")
		)
		(fp_line
			(start 1.38 -3.5)
			(end -1.38 -3.5)
			(stroke
				(width 0.2)
				(type solid)
			)
			(layer "F.SilkS")
		)
		(fp_line
			(start -3.5 -1.38)
			(end -3.5 1.38)
			(stroke
				(width 0.2)
				(type solid)
			)
			(layer "F.SilkS")
		)
		(pad "1" thru_hole rect
			(at 0 0 180)
			(size 2 2)
			(drill 1.5)
			(layers "*.Cu" "*.Mask")
			(remove_unused_layers no)
			(net "NetAN4_1")
		)
		(pad "2" thru_hole circle
			(at -2.54 -2.54 180)
			(size 2.2 2.2)
			(drill 1.7)
			(layers "*.Cu" "*.Mask")
			(remove_unused_layers no)
			(net "GND")
			(thermal_bridge_angle 90)
		)
		(pad "3" thru_hole circle
			(at -2.54 2.54 180)
			(size 2.2 2.2)
			(drill 1.7)
			(layers "*.Cu" "*.Mask")
			(remove_unused_layers no)
			(net "GND")
			(thermal_bridge_angle 90)
		)
		(pad "4" thru_hole circle
			(at 2.54 2.54 180)
			(size 2.2 2.2)
			(drill 1.7)
			(layers "*.Cu" "*.Mask")
			(remove_unused_layers no)
			(net "GND")
			(thermal_bridge_angle 90)
		)
		(pad "5" thru_hole circle
			(at 2.54 -2.54 180)
			(size 2.2 2.2)
			(drill 1.7)
			(layers "*.Cu" "*.Mask")
			(remove_unused_layers no)
			(net "GND")
			(thermal_bridge_angle 90)
		)
	)
)
